# T6G (Grand Teton) — schematic netlist excerpt (pin names and nets, part order shuffled) for the footprints in the layout excerpt that follows; sources: Cadence DE-HDL packaged netlist, KiCad conversion of 04192023_DAF0TMB3IC0_F0TG_MB_C_brd_V02_OCP.brd

PR470  Q_RES  10K 1% CHIP  pkg 0402LF  page 209 : A = PVDD18_S5_P0_FB ; B = PVDD18_S5_P0_RGND
R6292  Q_RES  1K 1% EMPTY  pkg 0402LF  page 179 : A = P3V3_AUX ; B = USB_HUB2_TI_GANGED
R1034  Q_RES  4.7K 5% EMPTY  pkg 0201LF  page 287 : A = P1V8_CPU0_RT_1D ; B = TEST2_RT_CPU0_P1

(kicad_pcb
	(version 20260206)
	(generator "pcbnew")
	(generator_version "10.0")
	(general
		(thickness 1.6)
		(legacy_teardrops no)
	)
	(paper "A4")
	(title_block
		(title "04192023_DAF0TMB3IC0_F0TG_MB_C_brd_V02_OCP.brd")
		(comment 1 "Grand Teton / footprints 4142-4144 of 8354")
	)
	(layers
		(0 "F.Cu" signal "TOP")
		(4 "In1.Cu" signal "GND")
		(6 "In2.Cu" signal "IN1")
		(8 "In3.Cu" signal "GND1")
		(10 "In4.Cu" signal "IN2")
		(12 "In5.Cu" signal "GND2")
		(14 "In6.Cu" signal "IN3")
		(16 "In7.Cu" signal "GND3")
		(18 "In8.Cu" signal "VCC")
		(20 "In9.Cu" signal "VCC1")
		(22 "In10.Cu" signal "GND4")
		(24 "In11.Cu" signal "IN4")
		(26 "In12.Cu" signal "GND5")
		(28 "In13.Cu" signal "IN5")
		(30 "In14.Cu" signal "GND6")
		(32 "In15.Cu" signal "IN6")
		(34 "In16.Cu" signal "GND7")
		(2 "B.Cu" signal "BOTTOM")
		(9 "F.Adhes" user "F.Adhesive")
		(11 "B.Adhes" user "B.Adhesive")
		(13 "F.Paste" user "Package Geometry/Pastemask Top")
		(15 "B.Paste" user "Package Geometry/Pastemask Bottom")
		(5 "F.SilkS" user "Ref Des/Silkscreen Top")
		(7 "B.SilkS" user "Ref Des/Silkscreen Bottom")
		(1 "F.Mask" user "Board Geometry/Soldermask Top")
		(3 "B.Mask" user "Board Geometry/Soldermask Bottom")
		(17 "Dwgs.User" user "User.Drawings")
		(19 "Cmts.User" user "User.Comments")
		(21 "Eco1.User" user "User.Eco1")
		(23 "Eco2.User" user "User.Eco2")
		(25 "Edge.Cuts" user "Board Geometry/Outline")
		(27 "Margin" user)
		(31 "F.CrtYd" user "Package Geometry/Place Bound Top")
		(29 "B.CrtYd" user "Package Geometry/Place Bound Bottom")
		(35 "F.Fab" user "Ref Des/Assembly Top")
		(33 "B.Fab" user "Ref Des/Assembly Bottom")
	)
	(footprint ""
		(layer "F.Cu")
		(at 330.269342 -392.1252)
		(property "Reference" "R1034"
			(at 0 0 0)
			(layer "F.SilkS")
			(hide yes)
			(effects
				(font
					(size 1.27 1.27)
				)
			)
		)
		(property "Value" ""
			(at 0 0 0)
			(layer "F.Fab")
			(effects
				(font
					(size 1.27 1.27)
				)
			)
		)
		(duplicate_pad_numbers_are_jumpers no)
		(fp_line
			(start -0.32512 -0.175006)
			(end 0.32512 -0.175006)
			(stroke
				(width 0.1)
				(type default)
			)
			(layer "F.Fab")
		)
		(fp_line
			(start -0.32512 0.175006)
			(end -0.32512 -0.175006)
			(stroke
				(width 0.1)
				(type default)
			)
			(layer "F.Fab")
		)
		(fp_line
			(start 0.32512 -0.175006)
			(end 0.32512 0.175006)
			(stroke
				(width 0.1)
				(type default)
			)
			(layer "F.Fab")
		)
		(fp_line
			(start 0.32512 0.175006)
			(end -0.32512 0.175006)
			(stroke
				(width 0.1)
				(type default)
			)
			(layer "F.Fab")
		)
		(pad "1" smd rect
			(at -0.2667 0)
			(size 0.3048 0.381)
			(layers "F.Cu" "F.Mask" "F.Paste")
			(net "P1V8_CPU0_RT_1D")
		)
		(pad "2" smd rect
			(at 0.2667 0 180)
			(size 0.3048 0.381)
			(layers "F.Cu" "F.Mask" "F.Paste")
			(net "TEST2_RT_CPU0_P1")
		)
	)
	(footprint ""
		(layer "F.Cu")
		(at 110.235238 -41.17975 -90)
		(property "Reference" "R6292"
			(at 0 0 270)
			(layer "F.SilkS")
			(hide yes)
			(effects
				(font
					(size 1.27 1.27)
				)
			)
		)
		(property "Value" ""
			(at 0 0 270)
			(layer "F.Fab")
			(effects
				(font
					(size 1.27 1.27)
				)
			)
		)
		(duplicate_pad_numbers_are_jumpers no)
		(fp_line
			(start -0.7874 0.4064)
			(end -0.7874 -0.4064)
			(stroke
				(width 0.1524)
				(type default)
			)
			(layer "F.SilkS")
		)
		(fp_line
			(start 0.7874 0.4064)
			(end -0.7874 0.4064)
			(stroke
				(width 0.1524)
				(type default)
			)
			(layer "F.SilkS")
		)
		(fp_line
			(start -0.7874 -0.4064)
			(end 0.7874 -0.4064)
			(stroke
				(width 0.1524)
				(type default)
			)
			(layer "F.SilkS")
		)
		(fp_line
			(start 0.7874 -0.4064)
			(end 0.7874 0.4064)
			(stroke
				(width 0.1524)
				(type default)
			)
			(layer "F.SilkS")
		)
		(fp_line
			(start -0.67945 0.3048)
			(end -0.67945 -0.305054)
			(stroke
				(width 0.1)
				(type default)
			)
			(layer "F.Fab")
		)
		(fp_line
			(start -0.12065 0.3048)
			(end -0.67945 0.3048)
			(stroke
				(width 0.1)
				(type default)
			)
			(layer "F.Fab")
		)
		(fp_line
			(start 0.120396 0.3048)
			(end 0.120396 0.2794)
			(stroke
				(width 0.1)
				(type default)
			)
			(layer "F.Fab")
		)
		(fp_line
			(start 0.67945 0.3048)
			(end 0.120396 0.3048)
			(stroke
				(width 0.1)
				(type default)
			)
			(layer "F.Fab")
		)
		(fp_line
			(start -0.12065 0.2794)
			(end -0.12065 0.3048)
			(stroke
				(width 0.1)
				(type default)
			)
			(layer "F.Fab")
		)
		(fp_line
			(start 0.120396 0.2794)
			(end -0.12065 0.2794)
			(stroke
				(width 0.1)
				(type default)
			)
			(layer "F.Fab")
		)
		(fp_line
			(start -0.12065 -0.2794)
			(end 0.12065 -0.2794)
			(stroke
				(width 0.1)
				(type default)
			)
			(layer "F.Fab")
		)
		(fp_line
			(start 0.12065 -0.2794)
			(end 0.12065 -0.3048)
			(stroke
				(width 0.1)
				(type default)
			)
			(layer "F.Fab")
		)
		(fp_line
			(start 0.12065 -0.3048)
			(end 0.67945 -0.3048)
			(stroke
				(width 0.1)
				(type default)
			)
			(layer "F.Fab")
		)
		(fp_line
			(start 0.67945 -0.3048)
			(end 0.67945 0.3048)
			(stroke
				(width 0.1)
				(type default)
			)
			(layer "F.Fab")
		)
		(fp_line
			(start -0.67945 -0.305054)
			(end -0.12065 -0.305054)
			(stroke
				(width 0.1)
				(type default)
			)
			(layer "F.Fab")
		)
		(fp_line
			(start -0.12065 -0.305054)
			(end -0.12065 -0.2794)
			(stroke
				(width 0.1)
				(type default)
			)
			(layer "F.Fab")
		)
		(pad "1" smd circle
			(at -0.40005 0 270)
			(size 0 0)
			(layers "F.Cu" "F.Mask" "F.Paste")
			(net "P3V3_AUX")
		)
		(pad "2" smd circle
			(at 0.40005 0 270)
			(size 0 0)
			(layers "F.Cu" "F.Mask" "F.Paste")
			(net "USB_HUB2_TI_GANGED")
		)
	)
	(footprint ""
		(layer "F.Cu")
		(at 331.156564 -138.890502 89.946)
		(property "Reference" "PR470"
			(at 0 0 89.946)
			(layer "F.SilkS")
			(hide yes)
			(effects
				(font
					(size 1.27 1.27)
				)
			)
		)
		(property "Value" ""
			(at 0 0 89.946)
			(layer "F.Fab")
			(effects
				(font
					(size 1.27 1.27)
				)
			)
		)
		(duplicate_pad_numbers_are_jumpers no)
		(fp_line
			(start -0.787275 -0.40642)
			(end 0.787525 -0.40638)
			(stroke
				(width 0.1524)
				(type default)
			)
			(layer "F.SilkS")
		)
		(fp_line
			(start 0.787525 -0.40638)
			(end 0.787275 0.40642)
			(stroke
				(width 0.1524)
				(type default)
			)
			(layer "F.SilkS")
		)
		(fp_line
			(start -0.787525 0.40638)
			(end -0.787275 -0.40642)
			(stroke
				(width 0.1524)
				(type default)
			)
			(layer "F.SilkS")
		)
		(fp_line
			(start 0.787275 0.40642)
			(end -0.787525 0.40638)
			(stroke
				(width 0.1524)
				(type default)
			)
			(layer "F.SilkS")
		)
		(fp_line
			(start -0.679484 -0.305176)
			(end -0.120683 -0.30494)
			(stroke
				(width 0.1)
				(type default)
			)
			(layer "F.Fab")
		)
		(fp_line
			(start -0.120683 -0.30494)
			(end -0.120659 -0.279286)
			(stroke
				(width 0.1)
				(type default)
			)
			(layer "F.Fab")
		)
		(fp_line
			(start 0.120617 -0.304914)
			(end 0.679417 -0.304678)
			(stroke
				(width 0.1)
				(type default)
			)
			(layer "F.Fab")
		)
		(fp_line
			(start 0.679417 -0.304678)
			(end 0.679484 0.304922)
			(stroke
				(width 0.1)
				(type default)
			)
			(layer "F.Fab")
		)
		(fp_line
			(start 0.120641 -0.279514)
			(end 0.120617 -0.304914)
			(stroke
				(width 0.1)
				(type default)
			)
			(layer "F.Fab")
		)
		(fp_line
			(start -0.120659 -0.279286)
			(end 0.120641 -0.279514)
			(stroke
				(width 0.1)
				(type default)
			)
			(layer "F.Fab")
		)
		(fp_line
			(start 0.120405 0.279287)
			(end -0.120641 0.279514)
			(stroke
				(width 0.1)
				(type default)
			)
			(layer "F.Fab")
		)
		(fp_line
			(start -0.120641 0.279514)
			(end -0.120617 0.304914)
			(stroke
				(width 0.1)
				(type default)
			)
			(layer "F.Fab")
		)
		(fp_line
			(start -0.679417 0.304678)
			(end -0.679484 -0.305176)
			(stroke
				(width 0.1)
				(type default)
			)
			(layer "F.Fab")
		)
		(fp_line
			(start 0.120429 0.304687)
			(end 0.120405 0.279287)
			(stroke
				(width 0.1)
				(type default)
			)
			(layer "F.Fab")
		)
		(fp_line
			(start -0.120617 0.304914)
			(end -0.679417 0.304678)
			(stroke
				(width 0.1)
				(type default)
			)
			(layer "F.Fab")
		)
		(fp_line
			(start 0.679484 0.304922)
			(end 0.120429 0.304687)
			(stroke
				(width 0.1)
				(type default)
			)
			(layer "F.Fab")
		)
		(pad "1" smd circle
			(at -0.40005 0 89.946)
			(size 0 0)
			(layers "F.Cu" "F.Mask" "F.Paste")
			(net "PVDD18_S5_P0_FB")
		)
		(pad "2" smd circle
			(at 0.40005 0 89.946)
			(size 0 0)
			(layers "F.Cu" "F.Mask" "F.Paste")
			(net "PVDD18_S5_P0_RGND")
		)
	)
)
